(kicad_pcb
	(version 20241229)
	(generator "pcbnew")
	(generator_version "9.0")
	(general
		(thickness 1.6)
		(legacy_teardrops no)
	)
	(paper "A4")
	(title_block
		(title "GMSL Deserializer")
		(date "2025-10-09")
		(rev "1.0.4")
		(company "Antmicro Ltd")
		(comment 1 "www.antmicro.com")
		(comment 9 "footprints 190-195 of 235")
	)
	(layers
		(0 "F.Cu" signal)
		(4 "In1.Cu" power)
		(6 "In2.Cu" power)
		(2 "B.Cu" signal)
		(9 "F.Adhes" user "F.Adhesive")
		(11 "B.Adhes" user "B.Adhesive")
		(13 "F.Paste" user)
		(15 "B.Paste" user)
		(5 "F.SilkS" user "F.Silkscreen")
		(7 "B.SilkS" user "B.Silkscreen")
		(1 "F.Mask" user)
		(3 "B.Mask" user)
		(17 "Dwgs.User" user "User.Drawings")
		(19 "Cmts.User" user "User.Comments")
		(21 "Eco1.User" user "User.Eco1")
		(23 "Eco2.User" user "User.Eco2")
		(25 "Edge.Cuts" user)
		(27 "Margin" user)
		(31 "F.CrtYd" user "F.Courtyard")
		(29 "B.CrtYd" user "B.Courtyard")
		(35 "F.Fab" user)
		(33 "B.Fab" user)
	)
	(footprint "antmicro-footprints:R_0402_1005Metric"
		(layer "B.Cu")
		(at 144.766904 96.385897 -90)
		(descr "Resistor SMD 0402")
		(tags "resistor SMD 0402")
		(property "Reference" "R81"
			(at -5.750329 -0.414422 90)
			(layer "B.SilkS")
			(effects
				(font
					(size 0.7 0.7)
					(thickness 0.15)
				)
				(justify right bottom mirror)
			)
		)
		(property "Value" "R_470R_0402"
			(at -1.011843 -1.772046 90)
			(layer "B.Fab")
			(effects
				(font
					(size 0.7 0.7)
					(thickness 0.15)
				)
				(justify left bottom mirror)
			)
		)
		(property "Datasheet" "https://www.bourns.com/docs/product-datasheets/cr.pdf"
			(at 0 0 90)
			(layer "F.Fab")
			(hide yes)
			(effects
				(font
					(size 1.27 1.27)
					(thickness 0.15)
				)
			)
		)
		(property "Description" "SMD Chip Resistor, 470 ohm, ± 1%, 62.5 mW, 0402 [1005 Metric], Thick Film, General Purpose"
			(at 0 0 90)
			(layer "F.Fab")
			(hide yes)
			(effects
				(font
					(size 1.27 1.27)
					(thickness 0.15)
				)
			)
		)
		(property "Author" "Antmicro"
			(at -25.166382 130.6418 135)
			(layer "B.Fab")
			(hide yes)
			(effects
				(font
					(size 1 1)
					(thickness 0.15)
				)
				(justify mirror)
			)
		)
		(property "License" "Apache-2.0"
			(at -25.166382 130.6418 135)
			(layer "B.Fab")
			(hide yes)
			(effects
				(font
					(size 1 1)
					(thickness 0.15)
				)
				(justify mirror)
			)
		)
		(property "MPN" "CR0402-FX-4700GLF"
			(at -25.166382 130.6418 135)
			(layer "B.Fab")
			(hide yes)
			(effects
				(font
					(size 1 1)
					(thickness 0.15)
				)
				(justify mirror)
			)
		)
		(property "Manufacturer" "Bourns"
			(at -25.166382 130.6418 135)
			(layer "B.Fab")
			(hide yes)
			(effects
				(font
					(size 1 1)
					(thickness 0.15)
				)
				(justify mirror)
			)
		)
		(property "Tolerance" "1%"
			(at -25.166382 130.6418 135)
			(layer "B.Fab")
			(hide yes)
			(effects
				(font
					(size 1 1)
					(thickness 0.15)
				)
				(justify mirror)
			)
		)
		(property "Val" "470R"
			(at -25.166382 130.6418 135)
			(layer "B.Fab")
			(hide yes)
			(effects
				(font
					(size 1 1)
					(thickness 0.15)
				)
				(justify mirror)
			)
		)
		(sheetname "/Power/")
		(sheetfile "power.kicad_sch")
		(attr smd)
		(fp_poly
			(pts
				(xy -0.925 0.47) (xy 0.925 0.47) (xy 0.925 -0.47) (xy -0.925 -0.47)
			)
			(stroke
				(width 0.05)
				(type default)
			)
			(fill no)
			(layer "B.CrtYd")
		)
		(fp_poly
			(pts
				(xy -0.5 0.25) (xy 0.5 0.25) (xy 0.5 -0.25) (xy -0.5 -0.25)
			)
			(stroke
				(width 0.15)
				(type solid)
			)
			(fill no)
			(layer "B.Fab")
		)
		(pad "1" smd roundrect
			(at -0.48 0 270)
			(size 0.59 0.64)
			(layers "B.Cu" "B.Mask" "B.Paste")
			(roundrect_rratio 0.25)
			(net 147 "Net-(D20-A)")
			(pintype "passive")
		)
		(pad "2" smd roundrect
			(at 0.48 0 270)
			(size 0.59 0.64)
			(layers "B.Cu" "B.Mask" "B.Paste")
			(roundrect_rratio 0.25)
			(net 5 "+5V")
			(pintype "passive")
		)
	)
	(footprint "antmicro-footprints:R_0402_1005Metric"
		(layer "B.Cu")
		(at 153.940161 96.375897 90)
		(descr "Resistor SMD 0402")
		(tags "resistor SMD 0402")
		(property "Reference" "R76"
			(at 5.748915 0.415836 90)
			(layer "B.SilkS")
			(effects
				(font
					(size 0.7 0.7)
					(thickness 0.15)
				)
				(justify right bottom mirror)
			)
		)
		(property "Value" "R_1k65_0402"
			(at -1.011843 -1.772046 90)
			(layer "B.Fab")
			(effects
				(font
					(size 0.7 0.7)
					(thickness 0.15)
				)
				(justify right bottom mirror)
			)
		)
		(property "Datasheet" "https://www.farnell.com/datasheets/3795017.pdf"
			(at 0 0 90)
			(layer "F.Fab")
			(hide yes)
			(effects
				(font
					(size 1.27 1.27)
					(thickness 0.15)
				)
			)
		)
		(property "Description" "SMD Chip Resistor, 1.65 kohm, ± 1%, 63 mW, 0402 [1005 Metric], Thick Film, General Purpose"
			(at 0 0 90)
			(layer "F.Fab")
			(hide yes)
			(effects
				(font
					(size 1.27 1.27)
					(thickness 0.15)
				)
			)
		)
		(property "Author" "Antmicro"
			(at 331.049173 54.373765 135)
			(layer "B.Fab")
			(hide yes)
			(effects
				(font
					(size 1 1)
					(thickness 0.15)
				)
				(justify mirror)
			)
		)
		(property "License" "Apache-2.0"
			(at 331.049173 54.373765 135)
			(layer "B.Fab")
			(hide yes)
			(effects
				(font
					(size 1 1)
					(thickness 0.15)
				)
				(justify mirror)
			)
		)
		(property "MPN" "RC0402FR-071K65L"
			(at 331.049173 54.373765 135)
			(layer "B.Fab")
			(hide yes)
			(effects
				(font
					(size 1 1)
					(thickness 0.15)
				)
				(justify mirror)
			)
		)
		(property "Manufacturer" "YAGEO"
			(at 331.049173 54.373765 135)
			(layer "B.Fab")
			(hide yes)
			(effects
				(font
					(size 1 1)
					(thickness 0.15)
				)
				(justify mirror)
			)
		)
		(property "Public" ""
			(at 331.049173 54.373765 135)
			(layer "B.Fab")
			(hide yes)
			(effects
				(font
					(size 1 1)
					(thickness 0.15)
				)
				(justify mirror)
			)
		)
		(property "Tolerance" "1%"
			(at 331.049173 54.373765 135)
			(layer "B.Fab")
			(hide yes)
			(effects
				(font
					(size 1 1)
					(thickness 0.15)
				)
				(justify mirror)
			)
		)
		(property "Val" "1k65"
			(at 331.049173 54.373765 135)
			(layer "B.Fab")
			(hide yes)
			(effects
				(font
					(size 1 1)
					(thickness 0.15)
				)
				(justify mirror)
			)
		)
		(sheetname "/Power/")
		(sheetfile "power.kicad_sch")
		(attr smd)
		(fp_poly
			(pts
				(xy -0.925 0.47) (xy 0.925 0.47) (xy 0.925 -0.47) (xy -0.925 -0.47)
			)
			(stroke
				(width 0.05)
				(type default)
			)
			(fill no)
			(layer "B.CrtYd")
		)
		(fp_poly
			(pts
				(xy -0.5 0.25) (xy 0.5 0.25) (xy 0.5 -0.25) (xy -0.5 -0.25)
			)
			(stroke
				(width 0.15)
				(type solid)
			)
			(fill no)
			(layer "B.Fab")
		)
		(pad "1" smd roundrect
			(at -0.48 0 90)
			(size 0.59 0.64)
			(layers "B.Cu" "B.Mask" "B.Paste")
			(roundrect_rratio 0.25)
			(net 1 "GND")
			(pintype "passive")
		)
		(pad "2" smd roundrect
			(at 0.48 0 90)
			(size 0.59 0.64)
			(layers "B.Cu" "B.Mask" "B.Paste")
			(roundrect_rratio 0.25)
			(net 112 "Net-(D15-C)")
			(pintype "passive")
		)
	)
	(footprint "antmicro-footprints:R_0402_1005Metric"
		(layer "B.Cu")
		(at 164.1 96.2 90)
		(descr "Resistor SMD 0402")
		(tags "resistor SMD 0402")
		(property "Reference" "R73"
			(at -1.05 1.45 90)
			(layer "B.SilkS")
			(effects
				(font
					(size 0.7 0.7)
					(thickness 0.15)
				)
				(justify right bottom mirror)
			)
		)
		(property "Value" "R_40k2_0402"
			(at -1.011843 -1.772047 90)
			(layer "B.Fab")
			(effects
				(font
					(size 0.7 0.7)
					(thickness 0.15)
				)
				(justify right bottom mirror)
			)
		)
		(property "Datasheet" "https://www.bourns.com/docs/product-datasheets/cr.pdf"
			(at 0 0 90)
			(layer "F.Fab")
			(hide yes)
			(effects
				(font
					(size 1.27 1.27)
					(thickness 0.15)
				)
			)
		)
		(property "Description" "SMD Chip Resistor, 40.2 kohm, ± 1%, 63 mW, 0402 [1005 Metric], Thick Film, General Purpose"
			(at 0 0 90)
			(layer "F.Fab")
			(hide yes)
			(effects
				(font
					(size 1.27 1.27)
					(thickness 0.15)
				)
			)
		)
		(property "Author" "Antmicro"
			(at 260.3 -67.9 0)
			(layer "B.Fab")
			(hide yes)
			(effects
				(font
					(size 1 1)
					(thickness 0.15)
				)
				(justify mirror)
			)
		)
		(property "License" "Apache-2.0"
			(at 260.3 -67.9 0)
			(layer "B.Fab")
			(hide yes)
			(effects
				(font
					(size 1 1)
					(thickness 0.15)
				)
				(justify mirror)
			)
		)
		(property "MPN" "CR0402-FX-4022GLF"
			(at 260.3 -67.9 0)
			(layer "B.Fab")
			(hide yes)
			(effects
				(font
					(size 1 1)
					(thickness 0.15)
				)
				(justify mirror)
			)
		)
		(property "Manufacturer" "Bourns"
			(at 260.3 -67.9 0)
			(layer "B.Fab")
			(hide yes)
			(effects
				(font
					(size 1 1)
					(thickness 0.15)
				)
				(justify mirror)
			)
		)
		(property "Public" ""
			(at 260.3 -67.9 0)
			(layer "B.Fab")
			(hide yes)
			(effects
				(font
					(size 1 1)
					(thickness 0.15)
				)
				(justify mirror)
			)
		)
		(property "Tolerance" "1%"
			(at 260.3 -67.9 0)
			(layer "B.Fab")
			(hide yes)
			(effects
				(font
					(size 1 1)
					(thickness 0.15)
				)
				(justify mirror)
			)
		)
		(property "Val" "40k2"
			(at 260.3 -67.9 0)
			(layer "B.Fab")
			(hide yes)
			(effects
				(font
					(size 1 1)
					(thickness 0.15)
				)
				(justify mirror)
			)
		)
		(sheetname "/Connectors/")
		(sheetfile "connectors.kicad_sch")
		(attr smd)
		(fp_rect
			(start -0.925 0.47)
			(end 0.925 -0.47)
			(stroke
				(width 0.05)
				(type default)
			)
			(fill no)
			(layer "B.CrtYd")
		)
		(fp_rect
			(start -0.5 0.25)
			(end 0.5 -0.25)
			(stroke
				(width 0.15)
				(type solid)
			)
			(fill no)
			(layer "B.Fab")
		)
		(pad "1" smd roundrect
			(at -0.48 0 90)
			(size 0.59 0.64)
			(layers "B.Cu" "B.Mask" "B.Paste")
			(roundrect_rratio 0.25)
			(net 84 "/Connectors/MFP4")
			(pintype "passive")
		)
		(pad "2" smd roundrect
			(at 0.48 0 90)
			(size 0.59 0.64)
			(layers "B.Cu" "B.Mask" "B.Paste")
			(roundrect_rratio 0.25)
			(net 146 "VDDIO")
			(pintype "passive")
		)
	)
	(footprint "antmicro-footprints:C_0402_1005Metric"
		(layer "B.Cu")
		(at 149.86 76.962 -135)
		(descr "Capacitor SMD 0402")
		(tags "capacitor SMD 0402")
		(property "Reference" "C44"
			(at -3.672905 -0.449013 45)
			(layer "B.SilkS")
			(effects
				(font
					(size 0.7 0.7)
					(thickness 0.15)
				)
				(justify left bottom mirror)
			)
		)
		(property "Value" "C_10u_0402"
			(at -1.022927 -2.155213 45)
			(layer "B.Fab")
			(effects
				(font
					(size 0.7 0.7)
					(thickness 0.15)
				)
				(justify left bottom mirror)
			)
		)
		(property "Datasheet" "https://www.yageo.com/en/Chart/Download/pdf/CC0402MRX5R5BB106"
			(at 0 0 225)
			(layer "F.Fab")
			(hide yes)
			(effects
				(font
					(size 1.27 1.27)
					(thickness 0.15)
				)
			)
		)
		(property "Description" "SMD Multilayer Ceramic Capacitor, 10 µF, 6.3 V, 0402 [1005 Metric], ± 20%, X5R, CC Series"
			(at 0 0 225)
			(layer "F.Fab")
			(hide yes)
			(effects
				(font
					(size 1.27 1.27)
					(thickness 0.15)
				)
			)
		)
		(property "Author" "Antmicro"
			(at 201.40667 237.349374 0)
			(layer "B.Fab")
			(hide yes)
			(effects
				(font
					(size 1 1)
					(thickness 0.15)
				)
				(justify mirror)
			)
		)
		(property "Dielectric" ""
			(at 201.40667 237.349374 0)
			(layer "B.Fab")
			(hide yes)
			(effects
				(font
					(size 1 1)
					(thickness 0.15)
				)
				(justify mirror)
			)
		)
		(property "License" "Apache-2.0"
			(at 201.40667 237.349374 0)
			(layer "B.Fab")
			(hide yes)
			(effects
				(font
					(size 1 1)
					(thickness 0.15)
				)
				(justify mirror)
			)
		)
		(property "MPN" "CC0402MRX5R5BB106"
			(at 201.40667 237.349374 0)
			(layer "B.Fab")
			(hide yes)
			(effects
				(font
					(size 1 1)
					(thickness 0.15)
				)
				(justify mirror)
			)
		)
		(property "Manufacturer" "YAGEO"
			(at 201.40667 237.349374 0)
			(layer "B.Fab")
			(hide yes)
			(effects
				(font
					(size 1 1)
					(thickness 0.15)
				)
				(justify mirror)
			)
		)
		(property "Val" "10u"
			(at 201.40667 237.349374 0)
			(layer "B.Fab")
			(hide yes)
			(effects
				(font
					(size 1 1)
					(thickness 0.15)
				)
				(justify mirror)
			)
		)
		(property "Voltage" ""
			(at 201.40667 237.349374 0)
			(layer "B.Fab")
			(hide yes)
			(effects
				(font
					(size 1 1)
					(thickness 0.15)
				)
				(justify mirror)
			)
		)
		(sheetname "/Deserializer/")
		(sheetfile "deserializer.kicad_sch")
		(attr smd)
		(fp_poly
			(pts
				(xy -0.925 0.47) (xy 0.925 0.47) (xy 0.925 -0.47) (xy -0.925 -0.47)
			)
			(stroke
				(width 0.05)
				(type default)
			)
			(fill no)
			(layer "B.CrtYd")
		)
		(fp_line
			(start 0.504 0.25)
			(end -0.494 0.25)
			(stroke
				(width 0.15)
				(type solid)
			)
			(layer "B.Fab")
		)
		(fp_line
			(start 0.504 -0.248)
			(end 0.504 0.25)
			(stroke
				(width 0.15)
				(type solid)
			)
			(layer "B.Fab")
		)
		(fp_line
			(start -0.494 0.25)
			(end -0.494 -0.248)
			(stroke
				(width 0.15)
				(type solid)
			)
			(layer "B.Fab")
		)
		(fp_line
			(start -0.494 -0.248)
			(end 0.504 -0.248)
			(stroke
				(width 0.15)
				(type solid)
			)
			(layer "B.Fab")
		)
		(pad "1" smd roundrect
			(at -0.48 0 225)
			(size 0.59 0.64)
			(layers "B.Cu" "B.Mask" "B.Paste")
			(roundrect_rratio 0.25)
			(net 1 "GND")
			(pintype "passive")
		)
		(pad "2" smd roundrect
			(at 0.48 0 225)
			(size 0.59 0.64)
			(layers "B.Cu" "B.Mask" "B.Paste")
			(roundrect_rratio 0.25)
			(net 28 "/Deserializer/CAP_VDD")
			(pintype "passive")
		)
	)
	(footprint "antmicro-footprints:C_0402_1005Metric"
		(layer "B.Cu")
		(at 145.034 74.93 -45)
		(descr "Capacitor SMD 0402")
		(tags "capacitor SMD 0402")
		(property "Reference" "C41"
			(at -1.51321 0.22729 315)
			(unlocked yes)
			(layer "B.SilkS")
			(effects
				(font
					(size 0.7 0.7)
					(thickness 0.15)
				)
				(justify left bottom mirror)
			)
		)
		(property "Value" "C_100n_0402"
			(at -1.022927 -2.155213 135)
			(layer "B.Fab")
			(effects
				(font
					(size 0.7 0.7)
					(thickness 0.15)
				)
				(justify left bottom mirror)
			)
		)
		(property "Datasheet" "https://www.murata.com/products/productdetail?partno=GRM155R61H104KE14%23"
			(at 0 0 315)
			(layer "F.Fab")
			(hide yes)
			(effects
				(font
					(size 1.27 1.27)
					(thickness 0.15)
				)
			)
		)
		(property "Description" "SMD Multilayer Ceramic Capacitor, 0.1 µF, 50 V, 0402 [1005 Metric], ± 10%, X5R, GRM Series"
			(at 0 0 315)
			(layer "F.Fab")
			(hide yes)
			(effects
				(font
					(size 1.27 1.27)
					(thickness 0.15)
				)
			)
		)
		(property "Author" "Antmicro"
			(at -10.504036 124.501014 0)
			(layer "B.Fab")
			(hide yes)
			(effects
				(font
					(size 1 1)
					(thickness 0.15)
				)
				(justify mirror)
			)
		)
		(property "Dielectric" "X5R"
			(at -10.504036 124.501014 0)
			(layer "B.Fab")
			(hide yes)
			(effects
				(font
					(size 1 1)
					(thickness 0.15)
				)
				(justify mirror)
			)
		)
		(property "License" "Apache-2.0"
			(at -10.504036 124.501014 0)
			(layer "B.Fab")
			(hide yes)
			(effects
				(font
					(size 1 1)
					(thickness 0.15)
				)
				(justify mirror)
			)
		)
		(property "MPN" "GRM155R61H104KE14D"
			(at -10.504036 124.501014 0)
			(layer "B.Fab")
			(hide yes)
			(effects
				(font
					(size 1 1)
					(thickness 0.15)
				)
				(justify mirror)
			)
		)
		(property "Manufacturer" "Murata"
			(at -10.504036 124.501014 0)
			(layer "B.Fab")
			(hide yes)
			(effects
				(font
					(size 1 1)
					(thickness 0.15)
				)
				(justify mirror)
			)
		)
		(property "Val" "100n"
			(at -10.504036 124.501014 0)
			(layer "B.Fab")
			(hide yes)
			(effects
				(font
					(size 1 1)
					(thickness 0.15)
				)
				(justify mirror)
			)
		)
		(property "Voltage" "50V"
			(at -10.504036 124.501014 0)
			(layer "B.Fab")
			(hide yes)
			(effects
				(font
					(size 1 1)
					(thickness 0.15)
				)
				(justify mirror)
			)
		)
		(sheetname "/Deserializer/")
		(sheetfile "deserializer.kicad_sch")
		(attr smd)
		(fp_poly
			(pts
				(xy -0.925 0.47) (xy 0.925 0.47) (xy 0.925 -0.47) (xy -0.925 -0.47)
			)
			(stroke
				(width 0.05)
				(type default)
			)
			(fill no)
			(layer "B.CrtYd")
		)
		(fp_line
			(start -0.494 0.25)
			(end -0.494 -0.248)
			(stroke
				(width 0.15)
				(type solid)
			)
			(layer "B.Fab")
		)
		(fp_line
			(start -0.494 -0.248)
			(end 0.504 -0.248)
			(stroke
				(width 0.15)
				(type solid)
			)
			(layer "B.Fab")
		)
		(fp_line
			(start 0.504 0.25)
			(end -0.494 0.25)
			(stroke
				(width 0.15)
				(type solid)
			)
			(layer "B.Fab")
		)
		(fp_line
			(start 0.504 -0.248)
			(end 0.504 0.25)
			(stroke
				(width 0.15)
				(type solid)
			)
			(layer "B.Fab")
		)
		(pad "1" smd roundrect
			(at -0.48 0 315)
			(size 0.59 0.64)
			(layers "B.Cu" "B.Mask" "B.Paste")
			(roundrect_rratio 0.25)
			(net 1 "GND")
			(pintype "passive")
		)
		(pad "2" smd roundrect
			(at 0.48 0 315)
			(size 0.59 0.64)
			(layers "B.Cu" "B.Mask" "B.Paste")
			(roundrect_rratio 0.25)
			(net 28 "/Deserializer/CAP_VDD")
			(pintype "passive")
		)
	)
	(footprint "antmicro-footprints:R_0402_1005Metric"
		(layer "B.Cu")
		(at 133.25 89.45 -90)
		(descr "Resistor SMD 0402")
		(tags "resistor SMD 0402")
		(property "Reference" "R72"
			(at 0.85 -0.45 90)
			(layer "B.SilkS")
			(effects
				(font
					(size 0.7 0.7)
					(thickness 0.15)
				)
				(justify left bottom mirror)
			)
		)
		(property "Value" "R_100k_0402"
			(at -1.011843 -1.772047 90)
			(layer "B.Fab")
			(effects
				(font
					(size 0.7 0.7)
					(thickness 0.15)
				)
				(justify left bottom mirror)
			)
		)
		(property "Datasheet" "https://www.bourns.com/docs/product-datasheets/cr.pdf"
			(at 0 0 270)
			(layer "F.Fab")
			(hide yes)
			(effects
				(font
					(size 1.27 1.27)
					(thickness 0.15)
				)
			)
		)
		(property "Description" "SMD Chip Resistor, 100 kohm, ± 1%, 62.5 mW, 0402 [1005 Metric], Thick Film, General Purpose"
			(at 0 0 270)
			(layer "F.Fab")
			(hide yes)
			(effects
				(font
					(size 1.27 1.27)
					(thickness 0.15)
				)
			)
		)
		(property "Author" "Antmicro"
			(at 43.8 222.7 0)
			(layer "B.Fab")
			(hide yes)
			(effects
				(font
					(size 1 1)
					(thickness 0.15)
				)
				(justify mirror)
			)
		)
		(property "License" "Apache-2.0"
			(at 43.8 222.7 0)
			(layer "B.Fab")
			(hide yes)
			(effects
				(font
					(size 1 1)
					(thickness 0.15)
				)
				(justify mirror)
			)
		)
		(property "MPN" "CR0402-FX-1003GLF"
			(at 43.8 222.7 0)
			(layer "B.Fab")
			(hide yes)
			(effects
				(font
					(size 1 1)
					(thickness 0.15)
				)
				(justify mirror)
			)
		)
		(property "Manufacturer" "Bourns"
			(at 43.8 222.7 0)
			(layer "B.Fab")
			(hide yes)
			(effects
				(font
					(size 1 1)
					(thickness 0.15)
				)
				(justify mirror)
			)
		)
		(property "Tolerance" "1%"
			(at 43.8 222.7 0)
			(layer "B.Fab")
			(hide yes)
			(effects
				(font
					(size 1 1)
					(thickness 0.15)
				)
				(justify mirror)
			)
		)
		(property "Val" "100k"
			(at 43.8 222.7 0)
			(layer "B.Fab")
			(hide yes)
			(effects
				(font
					(size 1 1)
					(thickness 0.15)
				)
				(justify mirror)
			)
		)
		(sheetname "/Power/")
		(sheetfile "power.kicad_sch")
		(attr smd)
		(fp_rect
			(start -0.925 0.47)
			(end 0.925 -0.47)
			(stroke
				(width 0.05)
				(type default)
			)
			(fill no)
			(layer "B.CrtYd")
		)
		(fp_rect
			(start -0.5 0.25)
			(end 0.5 -0.25)
			(stroke
				(width 0.15)
				(type solid)
			)
			(fill no)
			(layer "B.Fab")
		)
		(pad "1" smd roundrect
			(at -0.48 0 270)
			(size 0.59 0.64)
			(layers "B.Cu" "B.Mask" "B.Paste")
			(roundrect_rratio 0.25)
			(net 1 "GND")
			(pintype "passive")
		)
		(pad "2" smd roundrect
			(at 0.48 0 270)
			(size 0.59 0.64)
			(layers "B.Cu" "B.Mask" "B.Paste")
			(roundrect_rratio 0.25)
			(net 11 "/Power/OUT_1V2")
			(pintype "passive")
		)
	)
)
